(kicad_pcb
	(version 20260206)
	(generator "pcbnew")
	(generator_version "10.0")
	(general
		(thickness 1.6)
		(legacy_teardrops no)
	)
	(paper "A4")
	(title_block
		(title "v1-chassis-manager — T6M_CM_d_v01_1031_1645.brd")
		(comment 1 "Open CloudServer (Microsoft) / footprints 1480-1484 of 2512")
	)
	(layers
		(0 "F.Cu" signal "TOP")
		(4 "In1.Cu" signal "GND1")
		(6 "In2.Cu" signal "IN1")
		(8 "In3.Cu" signal "VCC1")
		(10 "In4.Cu" signal "VCC2")
		(12 "In5.Cu" signal "GND2")
		(14 "In6.Cu" signal "IN2")
		(16 "In7.Cu" signal "IN3")
		(18 "In8.Cu" signal "GND3")
		(2 "B.Cu" signal "BOTTOM")
		(9 "F.Adhes" user "F.Adhesive")
		(11 "B.Adhes" user "B.Adhesive")
		(13 "F.Paste" user "Package Geometry/Pastemask Top")
		(15 "B.Paste" user "Package Geometry/Pastemask Bottom")
		(5 "F.SilkS" user "Ref Des/Silkscreen Top")
		(7 "B.SilkS" user "Ref Des/Silkscreen Bottom")
		(1 "F.Mask" user "Board Geometry/Soldermask Top")
		(3 "B.Mask" user "Board Geometry/Soldermask Bottom")
		(17 "Dwgs.User" user "User.Drawings")
		(19 "Cmts.User" user "User.Comments")
		(21 "Eco1.User" user "User.Eco1")
		(23 "Eco2.User" user "User.Eco2")
		(25 "Edge.Cuts" user "Board Geometry/Outline")
		(27 "Margin" user)
		(31 "F.CrtYd" user "Package Geometry/Place Bound Top")
		(29 "B.CrtYd" user "Package Geometry/Place Bound Bottom")
		(35 "F.Fab" user "Ref Des/Assembly Top")
		(33 "B.Fab" user "Ref Des/Assembly Bottom")
	)
	(footprint ""
		(layer "F.Cu")
		(at 28.498546 -99.573842)
		(property "Reference" "R1152"
			(at 1.402334 0.434594 0)
			(unlocked yes)
			(layer "F.SilkS")
			(effects
				(font
					(size 0.7874 0.5842)
					(thickness 0.1524)
				)
				(justify left)
			)
		)
		(property "Value" ""
			(at 0 0 0)
			(layer "F.Fab")
			(effects
				(font
					(size 1.27 1.27)
				)
			)
		)
		(duplicate_pad_numbers_are_jumpers no)
		(fp_line
			(start -0.7874 -0.4064)
			(end 0.7874 -0.4064)
			(stroke
				(width 0.1524)
				(type default)
			)
			(layer "F.SilkS")
		)
		(fp_line
			(start -0.7874 0.4064)
			(end -0.7874 -0.4064)
			(stroke
				(width 0.1524)
				(type default)
			)
			(layer "F.SilkS")
		)
		(fp_line
			(start 0.7874 -0.4064)
			(end 0.7874 0.4064)
			(stroke
				(width 0.1524)
				(type default)
			)
			(layer "F.SilkS")
		)
		(fp_line
			(start 0.7874 0.4064)
			(end -0.7874 0.4064)
			(stroke
				(width 0.1524)
				(type default)
			)
			(layer "F.SilkS")
		)
		(fp_poly
			(pts
				(xy -0.508 0.2794) (xy -0.508 0.2286) (xy -0.635 0.2286) (xy -0.635 -0.254) (xy -0.5334 -0.254)
				(xy -0.5334 -0.2794) (xy 0.5334 -0.2794) (xy 0.5334 -0.254) (xy 0.635 -0.254) (xy 0.635 0.254) (xy 0.5334 0.254)
				(xy 0.5334 0.2794)
			)
			(stroke
				(width 0)
				(type default)
			)
			(fill no)
			(layer "F.CrtYd")
		)
		(pad "1" smd rect
			(at 0.40005 0)
			(size 0.4572 0.508)
			(layers "F.Cu" "F.Mask" "F.Paste")
			(net "GND")
		)
		(pad "2" smd rect
			(at -0.40005 0)
			(size 0.4572 0.508)
			(layers "F.Cu" "F.Mask" "F.Paste")
			(net "FRU_SYS_A0")
		)
	)
	(footprint ""
		(layer "F.Cu")
		(at -6.825488 -31.804102 90)
		(property "Reference" "J30"
			(at 1.18872 -6.71703 90)
			(unlocked yes)
			(layer "F.SilkS")
			(effects
				(font
					(size 0.7874 0.5842)
					(thickness 0.1524)
				)
				(justify left)
			)
		)
		(property "Value" ""
			(at 0 0 90)
			(layer "F.Fab")
			(effects
				(font
					(size 1.27 1.27)
				)
			)
		)
		(duplicate_pad_numbers_are_jumpers no)
		(fp_circle
			(center 4.064 -4.572)
			(end 4.064 -3.937)
			(stroke
				(width 0.05)
				(type default)
			)
			(fill no)
			(layer "Edge.Cuts")
		)
		(fp_circle
			(center 0 -4.572)
			(end 0 -3.937)
			(stroke
				(width 0.05)
				(type default)
			)
			(fill no)
			(layer "Edge.Cuts")
		)
		(fp_circle
			(center 4.064 0)
			(end 4.064 0.635)
			(stroke
				(width 0.05)
				(type default)
			)
			(fill no)
			(layer "Edge.Cuts")
		)
		(fp_circle
			(center 0 0)
			(end 0 0.635)
			(stroke
				(width 0.05)
				(type default)
			)
			(fill no)
			(layer "Edge.Cuts")
		)
		(fp_rect
			(start -1.27 1.27)
			(end 5.334 -5.842)
			(stroke
				(width 0)
				(type default)
			)
			(fill no)
			(layer "F.CrtYd")
		)
		(pad "" np_thru_hole circle
			(at 0 -4.572 90)
			(size 0.254 0.254)
			(drill 1.27)
			(layers "*.Cu" "*.Mask")
			(clearance 0.889)
			(thermal_gap 0.889)
		)
		(pad "" np_thru_hole circle
			(at 0 0 90)
			(size 0.254 0.254)
			(drill 1.27)
			(layers "*.Cu" "*.Mask")
			(clearance 0.889)
			(thermal_gap 0.889)
		)
		(pad "" np_thru_hole circle
			(at 4.064 -4.572 90)
			(size 0.254 0.254)
			(drill 1.27)
			(layers "*.Cu" "*.Mask")
			(clearance 0.889)
			(thermal_gap 0.889)
		)
		(pad "" np_thru_hole circle
			(at 4.064 0 90)
			(size 0.254 0.254)
			(drill 1.27)
			(layers "*.Cu" "*.Mask")
			(clearance 0.889)
			(thermal_gap 0.889)
		)
		(pad "1" thru_hole custom
			(at 1.397 -2.286 180)
			(size 0.266741 0.266741)
			(drill 0.254)
			(layers "*.Cu" "*.Mask")
			(remove_unused_layers no)
			(net "GND")
			(options
				(clearance outline)
				(anchor circle)
			)
			(primitives
				(gr_poly
					(pts
						(xy -0.979932 0.5334)
						(arc
							(start -0.979932 -0.078994)
							(mid -0.925932 -0.48038)
							(end -0.527812 -0.4064)
						)
						(arc
							(start -0.234188 -0.4064)
							(mid 0 -0.53341)
							(end 0.234188 -0.4064)
						)
						(arc
							(start 0.527812 -0.4064)
							(mid 0.925878 -0.480305)
							(end 0.979932 -0.078994)
						)
						(xy 0.979932 0.5334) (xy 0.548132 0.5334) (xy 0.548132 0.1016) (xy -0.548132 0.1016) (xy -0.548132 0.5334)
					)
					(width 0)
					(fill yes)
				)
			)
			(padstack
				(mode front_inner_back)
				(layer "Inner"
					(shape custom)
					(size 0.139735 0.139735)
					(options
						(anchor circle)
					)
					(primitives
						(gr_poly
							(pts
								(arc
									(start 0.26035 0.1016)
									(mid 0 0.279472)
									(end -0.26035 0.1016)
								)
								(arc
									(start -0.50165 0.1016)
									(mid -1.041472 0)
									(end -0.50165 -0.1016)
								)
								(arc
									(start -0.26035 -0.1016)
									(mid 0 -0.279472)
									(end 0.26035 -0.1016)
								)
								(arc
									(start 0.50165 -0.1016)
									(mid 1.041472 0)
									(end 0.50165 0.1016)
								)
							)
							(width 0)
							(fill yes)
						)
					)
				)
				(layer "B.Cu"
					(shape custom)
					(size 0.139735 0.139735)
					(options
						(anchor circle)
					)
					(primitives
						(gr_poly
							(pts
								(arc
									(start 0.26035 0.1016)
									(mid 0 0.279472)
									(end -0.26035 0.1016)
								)
								(arc
									(start -0.50165 0.1016)
									(mid -1.041472 0)
									(end -0.50165 -0.1016)
								)
								(arc
									(start -0.26035 -0.1016)
									(mid 0 -0.279472)
									(end 0.26035 -0.1016)
								)
								(arc
									(start 0.50165 -0.1016)
									(mid 1.041472 0)
									(end 0.50165 0.1016)
								)
							)
							(width 0)
							(fill yes)
						)
					)
				)
			)
		)
		(pad "2" smd rect
			(at 2.032 -2.060956 90)
			(size 0.3048 0.2032)
			(layers "F.Cu" "F.Mask" "F.Paste")
			(net "THRU_85_OHM")
		)
		(pad "3" smd rect
			(at 2.032 -2.511044 90)
			(size 0.3048 0.2032)
			(layers "F.Cu" "F.Mask" "F.Paste")
			(net "THRU_85_OHM")
		)
		(zone
			(layers "F.Cu" "B.Cu" "In1.Cu" "In2.Cu" "In3.Cu" "In4.Cu" "In5.Cu" "In6.Cu"
				"In7.Cu" "In8.Cu"
			)
			(hatch none 0.5)
			(connect_pads
				(clearance 0)
			)
			(min_thickness 0.25)
			(keepout
				(tracks not_allowed)
				(vias allowed)
				(pads allowed)
				(copperpour not_allowed)
				(footprints allowed)
			)
			(placement
				(enabled no)
				(sheetname "")
			)
			(fill
				(thermal_gap 0.5)
				(thermal_bridge_width 0.5)
				(island_removal_mode 0)
			)
			(polygon
				(pts
					(arc
						(start -11.397488 -36.757102)
						(mid -11.397488 -34.979102)
						(end -11.397488 -36.757102)
					)
				)
			)
		)
		(zone
			(layers "F.Cu" "B.Cu" "In1.Cu" "In2.Cu" "In3.Cu" "In4.Cu" "In5.Cu" "In6.Cu"
				"In7.Cu" "In8.Cu"
			)
			(hatch none 0.5)
			(connect_pads
				(clearance 0)
			)
			(min_thickness 0.25)
			(keepout
				(tracks not_allowed)
				(vias allowed)
				(pads allowed)
				(copperpour not_allowed)
				(footprints allowed)
			)
			(placement
				(enabled no)
				(sheetname "")
			)
			(fill
				(thermal_gap 0.5)
				(thermal_bridge_width 0.5)
				(island_removal_mode 0)
			)
			(polygon
				(pts
					(arc
						(start -11.397488 -32.693102)
						(mid -11.397488 -30.915102)
						(end -11.397488 -32.693102)
					)
				)
			)
		)
		(zone
			(layers "F.Cu" "B.Cu" "In1.Cu" "In2.Cu" "In3.Cu" "In4.Cu" "In5.Cu" "In6.Cu"
				"In7.Cu" "In8.Cu"
			)
			(hatch none 0.5)
			(connect_pads
				(clearance 0)
			)
			(min_thickness 0.25)
			(keepout
				(tracks not_allowed)
				(vias allowed)
				(pads allowed)
				(copperpour not_allowed)
				(footprints allowed)
			)
			(placement
				(enabled no)
				(sheetname "")
			)
			(fill
				(thermal_gap 0.5)
				(thermal_bridge_width 0.5)
				(island_removal_mode 0)
			)
			(polygon
				(pts
					(arc
						(start -6.825488 -36.757102)
						(mid -6.825488 -34.979102)
						(end -6.825488 -36.757102)
					)
				)
			)
		)
		(zone
			(layers "F.Cu" "B.Cu" "In1.Cu" "In2.Cu" "In3.Cu" "In4.Cu" "In5.Cu" "In6.Cu"
				"In7.Cu" "In8.Cu"
			)
			(hatch none 0.5)
			(connect_pads
				(clearance 0)
			)
			(min_thickness 0.25)
			(keepout
				(tracks not_allowed)
				(vias allowed)
				(pads allowed)
				(copperpour not_allowed)
				(footprints allowed)
			)
			(placement
				(enabled no)
				(sheetname "")
			)
			(fill
				(thermal_gap 0.5)
				(thermal_bridge_width 0.5)
				(island_removal_mode 0)
			)
			(polygon
				(pts
					(arc
						(start -6.825488 -32.693102)
						(mid -6.825488 -30.915102)
						(end -6.825488 -32.693102)
					)
				)
			)
		)
	)
	(footprint ""
		(layer "F.Cu")
		(at 120.620536 -153.898854 -90)
		(property "Reference" "R644"
			(at 111.266986 57.81802 90)
			(unlocked yes)
			(layer "F.SilkS")
			(effects
				(font
					(size 0.7874 0.5842)
					(thickness 0.1524)
				)
				(justify left)
			)
		)
		(property "Value" ""
			(at 0 0 270)
			(layer "F.Fab")
			(effects
				(font
					(size 1.27 1.27)
				)
			)
		)
		(duplicate_pad_numbers_are_jumpers no)
		(fp_line
			(start -0.7874 0.406146)
			(end -0.7874 -0.406146)
			(stroke
				(width 0.1524)
				(type default)
			)
			(layer "F.SilkS")
		)
		(fp_line
			(start 0.7874 0.406146)
			(end -0.7874 0.406146)
			(stroke
				(width 0.1524)
				(type default)
			)
			(layer "F.SilkS")
		)
		(fp_line
			(start -0.7874 -0.406146)
			(end 0.7874 -0.406146)
			(stroke
				(width 0.1524)
				(type default)
			)
			(layer "F.SilkS")
		)
		(fp_line
			(start 0.7874 -0.406146)
			(end 0.7874 0.406146)
			(stroke
				(width 0.1524)
				(type default)
			)
			(layer "F.SilkS")
		)
		(fp_poly
			(pts
				(xy -0.508 0.2794) (xy -0.508 0.2286) (xy -0.635 0.2286) (xy -0.635 -0.254) (xy -0.5334 -0.254)
				(xy -0.5334 -0.2794) (xy 0.5334 -0.2794) (xy 0.5334 -0.254) (xy 0.635 -0.254) (xy 0.635 0.254) (xy 0.5334 0.254)
				(xy 0.5334 0.2794)
			)
			(stroke
				(width 0)
				(type default)
			)
			(fill no)
			(layer "F.CrtYd")
		)
		(pad "1" smd rect
			(at 0.40005 0 270)
			(size 0.4572 0.508)
			(layers "F.Cu" "F.Mask" "F.Paste")
			(net "I2C_PSU1_SDA")
		)
		(pad "2" smd rect
			(at -0.40005 0 270)
			(size 0.4572 0.508)
			(layers "F.Cu" "F.Mask" "F.Paste")
			(net "I2C_PSU1_SDA_MOS")
		)
	)
	(footprint ""
		(layer "F.Cu")
		(at 137.39876 -108.370624 90)
		(property "Reference" "R19"
			(at -6.585204 0.466852 90)
			(unlocked yes)
			(layer "F.SilkS")
			(effects
				(font
					(size 0.7874 0.5842)
					(thickness 0.1524)
				)
				(justify left)
			)
		)
		(property "Value" ""
			(at 0 0 90)
			(layer "F.Fab")
			(effects
				(font
					(size 1.27 1.27)
				)
			)
		)
		(duplicate_pad_numbers_are_jumpers no)
		(fp_line
			(start 0.7874 -0.4064)
			(end 0.7874 0.4064)
			(stroke
				(width 0.1524)
				(type default)
			)
			(layer "F.SilkS")
		)
		(fp_line
			(start -0.7874 -0.4064)
			(end 0.7874 -0.4064)
			(stroke
				(width 0.1524)
				(type default)
			)
			(layer "F.SilkS")
		)
		(fp_line
			(start 0.7874 0.4064)
			(end -0.7874 0.4064)
			(stroke
				(width 0.1524)
				(type default)
			)
			(layer "F.SilkS")
		)
		(fp_line
			(start -0.7874 0.4064)
			(end -0.7874 -0.4064)
			(stroke
				(width 0.1524)
				(type default)
			)
			(layer "F.SilkS")
		)
		(fp_poly
			(pts
				(xy -0.508 0.2794) (xy -0.508 0.2286) (xy -0.635 0.2286) (xy -0.635 -0.254) (xy -0.5334 -0.254)
				(xy -0.5334 -0.2794) (xy 0.5334 -0.2794) (xy 0.5334 -0.254) (xy 0.635 -0.254) (xy 0.635 0.254) (xy 0.5334 0.254)
				(xy 0.5334 0.2794)
			)
			(stroke
				(width 0)
				(type default)
			)
			(fill no)
			(layer "F.CrtYd")
		)
		(pad "1" smd rect
			(at 0.40005 0 90)
			(size 0.4572 0.508)
			(layers "F.Cu" "F.Mask" "F.Paste")
			(net "CLKREQA_NODE1_N")
		)
		(pad "2" smd rect
			(at -0.40005 0 90)
			(size 0.4572 0.508)
			(layers "F.Cu" "F.Mask" "F.Paste")
			(net "P3V3_CLK_NODE1")
		)
	)
	(footprint ""
		(layer "F.Cu")
		(at 25.10536 -51.858418 90)
		(property "Reference" "U132"
			(at 0.0889 15.889986 90)
			(unlocked yes)
			(layer "F.SilkS")
			(effects
				(font
					(size 0.7874 0.5842)
					(thickness 0.1524)
				)
				(justify left)
			)
		)
		(property "Value" ""
			(at 0 0 90)
			(layer "F.Fab")
			(effects
				(font
					(size 1.27 1.27)
				)
			)
		)
		(duplicate_pad_numbers_are_jumpers no)
		(fp_line
			(start 3.400044 -0.575056)
			(end 3.400044 -0.446532)
			(stroke
				(width 0.1524)
				(type default)
			)
			(layer "F.SilkS")
		)
		(fp_line
			(start 0.299974 -0.575056)
			(end 1.499362 -0.57404)
			(stroke
				(width 0.1524)
				(type default)
			)
			(layer "F.SilkS")
		)
		(fp_line
			(start 2.16662 -0.57404)
			(end 3.400044 -0.575056)
			(stroke
				(width 0.1524)
				(type default)
			)
			(layer "F.SilkS")
		)
		(fp_line
			(start 1.499362 -0.57404)
			(end 1.84912 -0.067056)
			(stroke
				(width 0.1524)
				(type default)
			)
			(layer "F.SilkS")
		)
		(fp_line
			(start 0.299974 -0.421132)
			(end 0.299974 -0.575056)
			(stroke
				(width 0.1524)
				(type default)
			)
			(layer "F.SilkS")
		)
		(fp_line
			(start 1.84912 -0.067056)
			(end 2.16662 -0.57404)
			(stroke
				(width 0.1524)
				(type default)
			)
			(layer "F.SilkS")
		)
		(fp_line
			(start 3.400044 2.271268)
			(end 3.400044 2.525014)
			(stroke
				(width 0.1524)
				(type default)
			)
			(layer "F.SilkS")
		)
		(fp_line
			(start 3.400044 2.525014)
			(end 0.299974 2.525014)
			(stroke
				(width 0.1524)
				(type default)
			)
			(layer "F.SilkS")
		)
		(fp_line
			(start 0.299974 2.525014)
			(end 0.299974 2.271268)
			(stroke
				(width 0.1524)
				(type default)
			)
			(layer "F.SilkS")
		)
		(fp_circle
			(center 1.113282 -0.015494)
			(end 1.113282 0.211582)
			(stroke
				(width 0.1524)
				(type default)
			)
			(fill no)
			(layer "F.SilkS")
		)
		(fp_poly
			(pts
				(xy -1.030986 -1.434084) (xy -1.537208 -0.928116) (xy -0.516636 -0.439928)
			)
			(stroke
				(width 0)
				(type default)
			)
			(fill yes)
			(layer "F.SilkS")
		)
		(fp_poly
			(pts
				(xy 0.299974 2.525014) (xy 3.400044 2.525014) (xy 3.400044 2.219706) (xy 4.415282 2.219706) (xy 4.415282 -0.269494)
				(xy 3.400044 -0.269494) (xy 3.400044 -0.575056) (xy 0.299974 -0.575056) (xy 0.299974 -0.269494)
				(xy -0.715518 -0.269494) (xy -0.715518 2.219706) (xy 0.299974 2.219706)
			)
			(stroke
				(width 0)
				(type default)
			)
			(fill no)
			(layer "F.CrtYd")
		)
		(fp_line
			(start 3.400044 -0.575056)
			(end 3.400044 2.525014)
			(stroke
				(width 0.1)
				(type default)
			)
			(layer "F.Fab")
		)
		(fp_line
			(start 0.299974 -0.575056)
			(end 3.400044 -0.575056)
			(stroke
				(width 0.1)
				(type default)
			)
			(layer "F.Fab")
		)
		(fp_line
			(start 3.400044 2.525014)
			(end 0.299974 2.525014)
			(stroke
				(width 0.1)
				(type default)
			)
			(layer "F.Fab")
		)
		(fp_line
			(start 0.299974 2.525014)
			(end 0.299974 -0.575056)
			(stroke
				(width 0.1)
				(type default)
			)
			(layer "F.Fab")
		)
		(fp_poly
			(pts
				(xy -2.4892 -0.440944) (xy -2.4892 0.274828) (xy -1.4224 -0.1016)
			)
			(stroke
				(width 0)
				(type default)
			)
			(fill yes)
			(layer "F.Fab")
		)
		(fp_text user "8"
			(at 4.099306 -0.719328 0)
			(unlocked yes)
			(layer "F.SilkS")
			(effects
				(font
					(size 0.635 0.4064)
					(thickness 0.1524)
				)
				(justify left)
			)
		)
		(fp_text user "1"
			(at -1.166622 0.17526 0)
			(unlocked yes)
			(layer "F.SilkS")
			(effects
				(font
					(size 0.635 0.4064)
					(thickness 0.1524)
				)
				(justify left)
			)
		)
		(fp_text user "5"
			(at 3.778758 2.855722 0)
			(unlocked yes)
			(layer "F.SilkS")
			(effects
				(font
					(size 0.635 0.4064)
					(thickness 0.1524)
				)
				(justify left)
			)
		)
		(fp_text user "4"
			(at 0.01651 3.070098 0)
			(unlocked yes)
			(layer "F.SilkS")
			(effects
				(font
					(size 0.635 0.4064)
					(thickness 0.1524)
				)
				(justify left)
			)
		)
		(fp_text user "1"
			(at -1.397 -0.100101 90)
			(unlocked yes)
			(layer "F.Fab")
			(effects
				(font
					(size 0.786892 0.583946)
					(thickness 0.000001)
				)
				(justify left)
			)
		)
		(fp_text user "8"
			(at 4.572 -0.074701 90)
			(unlocked yes)
			(layer "F.Fab")
			(effects
				(font
					(size 0.786892 0.583946)
					(thickness 0.000001)
				)
				(justify left)
			)
		)
		(fp_text user "5"
			(at 4.5974 2.008099 90)
			(unlocked yes)
			(layer "F.Fab")
			(effects
				(font
					(size 0.786892 0.583946)
					(thickness 0.000001)
				)
				(justify left)
			)
		)
		(fp_text user "4"
			(at -1.4986 2.033499 90)
			(unlocked yes)
			(layer "F.Fab")
			(effects
				(font
					(size 0.786892 0.583946)
					(thickness 0.000001)
				)
				(justify left)
			)
		)
		(pad "1" smd rect
			(at 0 0)
			(size 0.4318 1.3208)
			(layers "F.Cu" "F.Mask" "F.Paste")
			(net "GFX_BUF_EN_N")
		)
		(pad "2" smd rect
			(at 0 0.649986)
			(size 0.4318 1.3208)
			(layers "F.Cu" "F.Mask" "F.Paste")
			(net "BMC_NODE1_GFX_VSYNC")
		)
		(pad "3" smd rect
			(at 0 1.299972)
			(size 0.4318 1.3208)
			(layers "F.Cu" "F.Mask" "F.Paste")
			(net "VGA_HSYNC")
		)
		(pad "4" smd rect
			(at 0 1.949958)
			(size 0.4318 1.3208)
			(layers "F.Cu" "F.Mask" "F.Paste")
			(net "GND")
		)
		(pad "5" smd rect
			(at 3.700018 1.949958)
			(size 0.4318 1.3208)
			(layers "F.Cu" "F.Mask" "F.Paste")
			(net "BMC_NODE1_GFX_HSYNC")
		)
		(pad "6" smd rect
			(at 3.700018 1.299972)
			(size 0.4318 1.3208)
			(layers "F.Cu" "F.Mask" "F.Paste")
			(net "VGA_VSYNC")
		)
		(pad "7" smd rect
			(at 3.700018 0.649986)
			(size 0.4318 1.3208)
			(layers "F.Cu" "F.Mask" "F.Paste")
			(net "GFX_BUF_EN_N")
		)
		(pad "8" smd rect
			(at 3.700018 0)
			(size 0.4318 1.3208)
			(layers "F.Cu" "F.Mask" "F.Paste")
			(net "P5V_NODE1")
		)
	)
)
